# BASEBOARD_FAB2 (Tioga Pass) — schematic netlist excerpt (pin names and nets, part order shuffled) for the footprints in the layout excerpt that follows; sources: Cadence DE-HDL packaged netlist, KiCad conversion of Wiwynn_Tioga_Pass_MB.brd

C7B3  CAP  1000PF 50V 10% X7R  pkg 0402LF  page 218 : A = PWRGD_PVDDQ_DEF_R ; B = GND
R2N5  RES  665 1.0% CHIP  pkg 0402  page 138 : A = P3V3_STBY ; B = SMB_SMLINK0_STBY_LVC3_SCL
U9F3  TTL1G07_A  74LVC1G07 IC  pkg SOP  page 151 : A = RST_BMC_DDR3_BUF_IN_N ; Y = RST_BMC_DDR3_R_N

(kicad_pcb
	(version 20260206)
	(generator "pcbnew")
	(generator_version "10.0")
	(general
		(thickness 1.6)
		(legacy_teardrops no)
	)
	(paper "A4")
	(title_block
		(title "Wiwynn_Tioga_Pass_MB.brd")
		(comment 1 "Tioga Pass / footprints 369-371 of 4770")
	)
	(layers
		(0 "F.Cu" signal "TOP")
		(4 "In1.Cu" signal "L2GND")
		(6 "In2.Cu" signal "L3")
		(8 "In3.Cu" signal "L4GND")
		(10 "In4.Cu" signal "L5")
		(12 "In5.Cu" signal "L6GND")
		(14 "In6.Cu" signal "L7VCC")
		(16 "In7.Cu" signal "L8VCC")
		(18 "In8.Cu" signal "L9GND")
		(20 "In9.Cu" signal "L10")
		(22 "In10.Cu" signal "L11GND")
		(24 "In11.Cu" signal "L12")
		(26 "In12.Cu" signal "L13GND")
		(2 "B.Cu" signal "BOTTOM")
		(9 "F.Adhes" user "F.Adhesive")
		(11 "B.Adhes" user "B.Adhesive")
		(13 "F.Paste" user "Package Geometry/Pastemask Top")
		(15 "B.Paste" user "Package Geometry/Pastemask Bottom")
		(5 "F.SilkS" user "Ref Des/Silkscreen Top")
		(7 "B.SilkS" user "Ref Des/Silkscreen Bottom")
		(1 "F.Mask" user "Board Geometry/Soldermask Top")
		(3 "B.Mask" user "Board Geometry/Soldermask Bottom")
		(17 "Dwgs.User" user "User.Drawings")
		(19 "Cmts.User" user "User.Comments")
		(21 "Eco1.User" user "User.Eco1")
		(23 "Eco2.User" user "User.Eco2")
		(25 "Edge.Cuts" user "Board Geometry/Outline")
		(27 "Margin" user)
		(31 "F.CrtYd" user "Package Geometry/Place Bound Top")
		(29 "B.CrtYd" user "Package Geometry/Place Bound Bottom")
		(35 "F.Fab" user "Ref Des/Assembly Top")
		(33 "B.Fab" user "Ref Des/Assembly Bottom")
	)
	(footprint ""
		(layer "F.Cu")
		(at 411.0355 -108.204 -90)
		(property "Reference" "R2N5"
			(at 0 0 270)
			(layer "F.SilkS")
			(hide yes)
			(effects
				(font
					(size 1.27 1.27)
				)
			)
		)
		(property "Value" ""
			(at 0 0 270)
			(layer "F.Fab")
			(effects
				(font
					(size 1.27 1.27)
				)
			)
		)
		(duplicate_pad_numbers_are_jumpers no)
		(fp_poly
			(pts
				(xy -0.2794 -0.1016) (xy 0.2794 -0.1016) (xy 0.2794 0.9906) (xy -0.2794 0.9906)
			)
			(stroke
				(width 0)
				(type default)
			)
			(fill no)
			(layer "F.CrtYd")
		)
		(fp_line
			(start -0.2794 0.9906)
			(end 0.2794 0.9906)
			(stroke
				(width 0.1)
				(type default)
			)
			(layer "F.Fab")
		)
		(fp_line
			(start 0.2794 0.9906)
			(end 0.2794 -0.1016)
			(stroke
				(width 0.1)
				(type default)
			)
			(layer "F.Fab")
		)
		(fp_line
			(start -0.2794 -0.1016)
			(end -0.2794 0.9906)
			(stroke
				(width 0.1)
				(type default)
			)
			(layer "F.Fab")
		)
		(fp_line
			(start 0.2794 -0.1016)
			(end -0.2794 -0.1016)
			(stroke
				(width 0.1)
				(type default)
			)
			(layer "F.Fab")
		)
		(pad "1" smd rect
			(at 0 0 270)
			(size 0.508 0.508)
			(layers "F.Cu" "F.Mask" "F.Paste")
			(net "P3V3_STBY")
		)
		(pad "2" smd rect
			(at 0 0.889 270)
			(size 0.508 0.508)
			(layers "F.Cu" "F.Mask" "F.Paste")
			(net "SMB_SMLINK0_STBY_LVC3_SCL")
		)
		(zone
			(layer "F.Cu")
			(hatch none 0.5)
			(connect_pads
				(clearance 0)
			)
			(min_thickness 0.25)
			(keepout
				(tracks not_allowed)
				(vias allowed)
				(pads allowed)
				(copperpour not_allowed)
				(footprints allowed)
			)
			(placement
				(enabled no)
				(sheetname "")
			)
			(fill
				(thermal_gap 0.5)
				(thermal_bridge_width 0.5)
				(island_removal_mode 0)
			)
			(polygon
				(pts
					(xy 410.4005 -108.458) (xy 410.4005 -107.95) (xy 410.7815 -107.95) (xy 410.7815 -108.458)
				)
			)
		)
		(zone
			(layer "F.Cu")
			(hatch none 0.5)
			(connect_pads
				(clearance 0)
			)
			(min_thickness 0.25)
			(keepout
				(tracks allowed)
				(vias not_allowed)
				(pads allowed)
				(copperpour not_allowed)
				(footprints allowed)
			)
			(placement
				(enabled no)
				(sheetname "")
			)
			(fill
				(thermal_gap 0.5)
				(thermal_bridge_width 0.5)
				(island_removal_mode 0)
			)
			(polygon
				(pts
					(xy 410.7815 -108.458) (xy 410.7815 -107.95) (xy 410.4005 -107.95) (xy 410.4005 -108.458)
				)
			)
		)
	)
	(footprint ""
		(layer "F.Cu")
		(at 361.188 -133.985)
		(property "Reference" "C7B3"
			(at 0 0 0)
			(layer "F.SilkS")
			(hide yes)
			(effects
				(font
					(size 1.27 1.27)
				)
			)
		)
		(property "Value" ""
			(at 0 0 0)
			(layer "F.Fab")
			(effects
				(font
					(size 1.27 1.27)
				)
			)
		)
		(duplicate_pad_numbers_are_jumpers no)
		(fp_poly
			(pts
				(xy 0.3048 -0.1016) (xy 0.3048 0.9906) (xy -0.3048 0.9906) (xy -0.3048 -0.1016)
			)
			(stroke
				(width 0)
				(type default)
			)
			(fill no)
			(layer "F.CrtYd")
		)
		(fp_line
			(start -0.3048 -0.1016)
			(end -0.3048 0.9906)
			(stroke
				(width 0.1)
				(type default)
			)
			(layer "F.Fab")
		)
		(fp_line
			(start -0.3048 0.9906)
			(end 0.3048 0.9906)
			(stroke
				(width 0.1)
				(type default)
			)
			(layer "F.Fab")
		)
		(fp_line
			(start 0.3048 -0.1016)
			(end -0.3048 -0.1016)
			(stroke
				(width 0.1)
				(type default)
			)
			(layer "F.Fab")
		)
		(fp_line
			(start 0.3048 0.9906)
			(end 0.3048 -0.1016)
			(stroke
				(width 0.1)
				(type default)
			)
			(layer "F.Fab")
		)
		(pad "1" smd rect
			(at 0 0)
			(size 0.508 0.508)
			(layers "F.Cu" "F.Mask" "F.Paste")
			(net "PWRGD_PVDDQ_DEF_R")
		)
		(pad "2" smd rect
			(at 0 0.889)
			(size 0.508 0.508)
			(layers "F.Cu" "F.Mask" "F.Paste")
			(net "GND")
		)
		(zone
			(layer "F.Cu")
			(hatch none 0.5)
			(connect_pads
				(clearance 0)
			)
			(min_thickness 0.25)
			(keepout
				(tracks allowed)
				(vias not_allowed)
				(pads allowed)
				(copperpour not_allowed)
				(footprints allowed)
			)
			(placement
				(enabled no)
				(sheetname "")
			)
			(fill
				(thermal_gap 0.5)
				(thermal_bridge_width 0.5)
				(island_removal_mode 0)
			)
			(polygon
				(pts
					(xy 360.934 -133.731) (xy 361.442 -133.731) (xy 361.442 -133.35) (xy 360.934 -133.35)
				)
			)
		)
		(zone
			(layer "F.Cu")
			(hatch none 0.5)
			(connect_pads
				(clearance 0)
			)
			(min_thickness 0.25)
			(keepout
				(tracks not_allowed)
				(vias allowed)
				(pads allowed)
				(copperpour not_allowed)
				(footprints allowed)
			)
			(placement
				(enabled no)
				(sheetname "")
			)
			(fill
				(thermal_gap 0.5)
				(thermal_bridge_width 0.5)
				(island_removal_mode 0)
			)
			(polygon
				(pts
					(xy 360.934 -133.35) (xy 361.442 -133.35) (xy 361.442 -133.731) (xy 360.934 -133.731)
				)
			)
		)
	)
	(footprint ""
		(layer "F.Cu")
		(at 457.2 -31.735014 180)
		(property "Reference" "U9F3"
			(at -0.508 2.56667 180)
			(unlocked yes)
			(layer "F.SilkS")
			(effects
				(font
					(size 0.7874 0.5842)
					(thickness 0.1524)
				)
				(justify left)
			)
		)
		(property "Value" ""
			(at 0 0 180)
			(layer "F.Fab")
			(effects
				(font
					(size 1.27 1.27)
				)
			)
		)
		(duplicate_pad_numbers_are_jumpers no)
		(fp_circle
			(center -0.90805 -0.431546)
			(end -1.03505 -0.431546)
			(stroke
				(width 0.254)
				(type default)
			)
			(fill no)
			(layer "F.SilkS")
		)
		(fp_poly
			(pts
				(xy 0.21463 -0.450088) (xy 1.56337 -0.450088) (xy 1.56337 1.75006) (xy 0.21463 1.75006)
			)
			(stroke
				(width 0)
				(type default)
			)
			(fill no)
			(layer "F.CrtYd")
		)
		(fp_line
			(start 1.56337 1.75006)
			(end 0.21463 1.75006)
			(stroke
				(width 0.1)
				(type default)
			)
			(layer "F.Fab")
		)
		(fp_line
			(start 1.56337 -0.450088)
			(end 1.56337 1.75006)
			(stroke
				(width 0.1)
				(type default)
			)
			(layer "F.Fab")
		)
		(fp_line
			(start 0.21463 1.75006)
			(end 0.21463 -0.450088)
			(stroke
				(width 0.1)
				(type default)
			)
			(layer "F.Fab")
		)
		(fp_line
			(start 0.21463 -0.450088)
			(end 1.56337 -0.450088)
			(stroke
				(width 0.1)
				(type default)
			)
			(layer "F.Fab")
		)
		(fp_circle
			(center -0.4699 -0.8382)
			(end -0.5969 -0.8382)
			(stroke
				(width 0.254)
				(type default)
			)
			(fill no)
			(layer "F.Fab")
		)
		(pad "1" smd rect
			(at 0 0 180)
			(size 1.016 0.381)
			(layers "F.Cu" "F.Mask" "F.Paste")
			(net "Net_6467")
		)
		(pad "2" smd rect
			(at 0 0.649986 180)
			(size 1.016 0.381)
			(layers "F.Cu" "F.Mask" "F.Paste")
			(net "RST_BMC_DDR3_BUF_IN_N")
		)
		(pad "3" smd rect
			(at 0 1.299972 180)
			(size 1.016 0.381)
			(layers "F.Cu" "F.Mask" "F.Paste")
			(net "GND")
		)
		(pad "4" smd rect
			(at 1.778 1.299972 180)
			(size 1.016 0.381)
			(layers "F.Cu" "F.Mask" "F.Paste")
			(net "RST_BMC_DDR3_R_N")
		)
		(pad "5" smd rect
			(at 1.778 0 180)
			(size 1.016 0.381)
			(layers "F.Cu" "F.Mask" "F.Paste")
			(net "P3V3_STBY")
		)
	)
)
